FILE_TYPE = MULTI_PHYS_TABLE;
PART 'SCONN288_H44441003'
{====================================================================================================================================================================================================================}
:PACK_TYPE | MATERIAL | PART_NUMBER     = EnvComp  |   PART_NUMBER |  JEDEC_TYPE               | DESCRIPTION                                         | CLASS | COMPONENT_TYPE | HEIGHT     | LPID     | SPEED_URL | Status |RPL| AML | Bus_Unit | Days ;
{===================================================================================================================================================================================================================}
'PIP'      | 'SCONN'  | 'H44441-003'(!) = ''       |  'H44441-003' | 'SCONN288_H44441003_PIP'  | '(USE SYM 1-4)CONN,CEDG,288P,DDR4,VT,0.85mm,SMT,BK' | 'IO'  | 'SMTCONN'      | '0.839 IN' |  '3551'  | 'http://speed.intel.com:8081/speed/module/pdm/item/pdm_item_detail_direct.asp?item_cde=H44441-003&item_rev=01&url_param=unused' | '' | '' | '' | '' | '' 
'PIP'      | 'EMPTY'  | 'H44441-003'(!) = ''       |  'H44441-003' | 'SCONN288_H44441003_PIP'  | '(USE SYM 1-4)CONN,CEDG,288P,DDR4,VT,0.85mm,SMT,BK' | 'IO'  | 'SMTCONN'      | '0.839 IN' |  '3551'  | 'http://speed.intel.com:8081/speed/module/pdm/item/pdm_item_detail_direct.asp?item_cde=H44441-003&item_rev=01&url_param=unused' | '' | '' | '' | '' | '' 
END_PART
END.
